# T6G (Grand Teton) — schematic netlist excerpt (pin names and nets, part order shuffled) for the footprints in the layout excerpt that follows; sources: Cadence DE-HDL packaged netlist, KiCad conversion of 04192023_DAF0TMB3IC0_F0TG_MB_C_brd_V02_OCP.brd

R6320  Q_RES  10K 1% EMPTY  pkg 0402LF  page 178 : A = P3V3_AUX ; B = USB_HUB2_MRP_RESET_N
C6701  Q_CAP_DIFFBUS  DIFF BUS_0.22UF 6.3V 20% X6S  pkg C0201  page 341 : \1\ = P5E_CPU1_P2_TX_BUF_C_DP<4> ; \2\ = P5E_CPU1_P2_TX_BUF_DP<4>
R945  Q_RES  4.7K 5% CHIP  pkg 0402LF  page 166 : A = P3V3_AUX ; B = FM_SMERR_BUF_R_LED_N

(kicad_pcb
	(version 20260206)
	(generator "pcbnew")
	(generator_version "10.0")
	(general
		(thickness 1.6)
		(legacy_teardrops no)
	)
	(paper "A4")
	(title_block
		(title "04192023_DAF0TMB3IC0_F0TG_MB_C_brd_V02_OCP.brd")
		(comment 1 "Grand Teton / footprints 196-198 of 8354")
	)
	(layers
		(0 "F.Cu" signal "TOP")
		(4 "In1.Cu" signal "GND")
		(6 "In2.Cu" signal "IN1")
		(8 "In3.Cu" signal "GND1")
		(10 "In4.Cu" signal "IN2")
		(12 "In5.Cu" signal "GND2")
		(14 "In6.Cu" signal "IN3")
		(16 "In7.Cu" signal "GND3")
		(18 "In8.Cu" signal "VCC")
		(20 "In9.Cu" signal "VCC1")
		(22 "In10.Cu" signal "GND4")
		(24 "In11.Cu" signal "IN4")
		(26 "In12.Cu" signal "GND5")
		(28 "In13.Cu" signal "IN5")
		(30 "In14.Cu" signal "GND6")
		(32 "In15.Cu" signal "IN6")
		(34 "In16.Cu" signal "GND7")
		(2 "B.Cu" signal "BOTTOM")
		(9 "F.Adhes" user "F.Adhesive")
		(11 "B.Adhes" user "B.Adhesive")
		(13 "F.Paste" user "Package Geometry/Pastemask Top")
		(15 "B.Paste" user "Package Geometry/Pastemask Bottom")
		(5 "F.SilkS" user "Ref Des/Silkscreen Top")
		(7 "B.SilkS" user "Ref Des/Silkscreen Bottom")
		(1 "F.Mask" user "Board Geometry/Soldermask Top")
		(3 "B.Mask" user "Board Geometry/Soldermask Bottom")
		(17 "Dwgs.User" user "User.Drawings")
		(19 "Cmts.User" user "User.Comments")
		(21 "Eco1.User" user "User.Eco1")
		(23 "Eco2.User" user "User.Eco2")
		(25 "Edge.Cuts" user "Board Geometry/Outline")
		(27 "Margin" user)
		(31 "F.CrtYd" user "Package Geometry/Place Bound Top")
		(29 "B.CrtYd" user "Package Geometry/Place Bound Bottom")
		(35 "F.Fab" user "Ref Des/Assembly Top")
		(33 "B.Fab" user "Ref Des/Assembly Bottom")
	)
	(footprint ""
		(layer "F.Cu")
		(at 128.036066 -408.517344 -90)
		(property "Reference" "C6701"
			(at 0 0 270)
			(layer "F.SilkS")
			(hide yes)
			(effects
				(font
					(size 1.27 1.27)
				)
			)
		)
		(property "Value" ""
			(at 0 0 270)
			(layer "F.Fab")
			(effects
				(font
					(size 1.27 1.27)
				)
			)
		)
		(duplicate_pad_numbers_are_jumpers no)
		(fp_line
			(start -0.299974 0.150114)
			(end -0.299974 -0.150114)
			(stroke
				(width 0.1)
				(type default)
			)
			(layer "F.Fab")
		)
		(fp_line
			(start 0.299974 0.150114)
			(end -0.299974 0.150114)
			(stroke
				(width 0.1)
				(type default)
			)
			(layer "F.Fab")
		)
		(fp_line
			(start -0.299974 -0.150114)
			(end 0.299974 -0.150114)
			(stroke
				(width 0.1)
				(type default)
			)
			(layer "F.Fab")
		)
		(fp_line
			(start 0.299974 -0.150114)
			(end 0.299974 0.150114)
			(stroke
				(width 0.1)
				(type default)
			)
			(layer "F.Fab")
		)
		(pad "1" smd rect
			(at -0.2667 0 270)
			(size 0.3048 0.381)
			(layers "F.Cu" "F.Mask" "F.Paste")
			(net "P5E_CPU1_P2_TX_BUF_C_DP<4>")
		)
		(pad "2" smd rect
			(at 0.2667 0 270)
			(size 0.3048 0.381)
			(layers "F.Cu" "F.Mask" "F.Paste")
			(net "P5E_CPU1_P2_TX_BUF_DP<4>")
		)
	)
	(footprint ""
		(layer "F.Cu")
		(at 343.458546 -23.8887 -90)
		(property "Reference" "R945"
			(at 0 0 270)
			(layer "F.SilkS")
			(hide yes)
			(effects
				(font
					(size 1.27 1.27)
				)
			)
		)
		(property "Value" ""
			(at 0 0 270)
			(layer "F.Fab")
			(effects
				(font
					(size 1.27 1.27)
				)
			)
		)
		(duplicate_pad_numbers_are_jumpers no)
		(fp_line
			(start -0.7874 0.4064)
			(end -0.7874 -0.4064)
			(stroke
				(width 0.1524)
				(type default)
			)
			(layer "F.SilkS")
		)
		(fp_line
			(start 0.7874 0.4064)
			(end -0.7874 0.4064)
			(stroke
				(width 0.1524)
				(type default)
			)
			(layer "F.SilkS")
		)
		(fp_line
			(start -0.7874 -0.4064)
			(end 0.7874 -0.4064)
			(stroke
				(width 0.1524)
				(type default)
			)
			(layer "F.SilkS")
		)
		(fp_line
			(start 0.7874 -0.4064)
			(end 0.7874 0.4064)
			(stroke
				(width 0.1524)
				(type default)
			)
			(layer "F.SilkS")
		)
		(fp_line
			(start -0.67945 0.3048)
			(end -0.67945 -0.305054)
			(stroke
				(width 0.1)
				(type default)
			)
			(layer "F.Fab")
		)
		(fp_line
			(start -0.12065 0.3048)
			(end -0.67945 0.3048)
			(stroke
				(width 0.1)
				(type default)
			)
			(layer "F.Fab")
		)
		(fp_line
			(start 0.120396 0.3048)
			(end 0.120396 0.2794)
			(stroke
				(width 0.1)
				(type default)
			)
			(layer "F.Fab")
		)
		(fp_line
			(start 0.67945 0.3048)
			(end 0.120396 0.3048)
			(stroke
				(width 0.1)
				(type default)
			)
			(layer "F.Fab")
		)
		(fp_line
			(start -0.12065 0.2794)
			(end -0.12065 0.3048)
			(stroke
				(width 0.1)
				(type default)
			)
			(layer "F.Fab")
		)
		(fp_line
			(start 0.120396 0.2794)
			(end -0.12065 0.2794)
			(stroke
				(width 0.1)
				(type default)
			)
			(layer "F.Fab")
		)
		(fp_line
			(start -0.12065 -0.2794)
			(end 0.12065 -0.2794)
			(stroke
				(width 0.1)
				(type default)
			)
			(layer "F.Fab")
		)
		(fp_line
			(start 0.12065 -0.2794)
			(end 0.12065 -0.3048)
			(stroke
				(width 0.1)
				(type default)
			)
			(layer "F.Fab")
		)
		(fp_line
			(start 0.12065 -0.3048)
			(end 0.67945 -0.3048)
			(stroke
				(width 0.1)
				(type default)
			)
			(layer "F.Fab")
		)
		(fp_line
			(start 0.67945 -0.3048)
			(end 0.67945 0.3048)
			(stroke
				(width 0.1)
				(type default)
			)
			(layer "F.Fab")
		)
		(fp_line
			(start -0.67945 -0.305054)
			(end -0.12065 -0.305054)
			(stroke
				(width 0.1)
				(type default)
			)
			(layer "F.Fab")
		)
		(fp_line
			(start -0.12065 -0.305054)
			(end -0.12065 -0.2794)
			(stroke
				(width 0.1)
				(type default)
			)
			(layer "F.Fab")
		)
		(pad "1" smd circle
			(at -0.40005 0 270)
			(size 0 0)
			(layers "F.Cu" "F.Mask" "F.Paste")
			(net "P3V3_AUX")
		)
		(pad "2" smd circle
			(at 0.40005 0 270)
			(size 0 0)
			(layers "F.Cu" "F.Mask" "F.Paste")
			(net "FM_SMERR_BUF_R_LED_N")
		)
	)
	(footprint ""
		(layer "F.Cu")
		(at 103.453946 -54.882034 -90)
		(property "Reference" "R6320"
			(at 0 0 270)
			(layer "F.SilkS")
			(hide yes)
			(effects
				(font
					(size 1.27 1.27)
				)
			)
		)
		(property "Value" ""
			(at 0 0 270)
			(layer "F.Fab")
			(effects
				(font
					(size 1.27 1.27)
				)
			)
		)
		(duplicate_pad_numbers_are_jumpers no)
		(fp_line
			(start -0.7874 0.4064)
			(end -0.7874 -0.4064)
			(stroke
				(width 0.1524)
				(type default)
			)
			(layer "F.SilkS")
		)
		(fp_line
			(start 0.7874 0.4064)
			(end -0.7874 0.4064)
			(stroke
				(width 0.1524)
				(type default)
			)
			(layer "F.SilkS")
		)
		(fp_line
			(start -0.7874 -0.4064)
			(end 0.7874 -0.4064)
			(stroke
				(width 0.1524)
				(type default)
			)
			(layer "F.SilkS")
		)
		(fp_line
			(start 0.7874 -0.4064)
			(end 0.7874 0.4064)
			(stroke
				(width 0.1524)
				(type default)
			)
			(layer "F.SilkS")
		)
		(fp_line
			(start -0.67945 0.3048)
			(end -0.67945 -0.305054)
			(stroke
				(width 0.1)
				(type default)
			)
			(layer "F.Fab")
		)
		(fp_line
			(start -0.12065 0.3048)
			(end -0.67945 0.3048)
			(stroke
				(width 0.1)
				(type default)
			)
			(layer "F.Fab")
		)
		(fp_line
			(start 0.120396 0.3048)
			(end 0.120396 0.2794)
			(stroke
				(width 0.1)
				(type default)
			)
			(layer "F.Fab")
		)
		(fp_line
			(start 0.67945 0.3048)
			(end 0.120396 0.3048)
			(stroke
				(width 0.1)
				(type default)
			)
			(layer "F.Fab")
		)
		(fp_line
			(start -0.12065 0.2794)
			(end -0.12065 0.3048)
			(stroke
				(width 0.1)
				(type default)
			)
			(layer "F.Fab")
		)
		(fp_line
			(start 0.120396 0.2794)
			(end -0.12065 0.2794)
			(stroke
				(width 0.1)
				(type default)
			)
			(layer "F.Fab")
		)
		(fp_line
			(start -0.12065 -0.2794)
			(end 0.12065 -0.2794)
			(stroke
				(width 0.1)
				(type default)
			)
			(layer "F.Fab")
		)
		(fp_line
			(start 0.12065 -0.2794)
			(end 0.12065 -0.3048)
			(stroke
				(width 0.1)
				(type default)
			)
			(layer "F.Fab")
		)
		(fp_line
			(start 0.12065 -0.3048)
			(end 0.67945 -0.3048)
			(stroke
				(width 0.1)
				(type default)
			)
			(layer "F.Fab")
		)
		(fp_line
			(start 0.67945 -0.3048)
			(end 0.67945 0.3048)
			(stroke
				(width 0.1)
				(type default)
			)
			(layer "F.Fab")
		)
		(fp_line
			(start -0.67945 -0.305054)
			(end -0.12065 -0.305054)
			(stroke
				(width 0.1)
				(type default)
			)
			(layer "F.Fab")
		)
		(fp_line
			(start -0.12065 -0.305054)
			(end -0.12065 -0.2794)
			(stroke
				(width 0.1)
				(type default)
			)
			(layer "F.Fab")
		)
		(pad "1" smd circle
			(at -0.40005 0 270)
			(size 0 0)
			(layers "F.Cu" "F.Mask" "F.Paste")
			(net "P3V3_AUX")
		)
		(pad "2" smd circle
			(at 0.40005 0 270)
			(size 0 0)
			(layers "F.Cu" "F.Mask" "F.Paste")
			(net "USB_HUB2_MRP_RESET_N")
		)
	)
)
